# S9S_MB_2U (Grand Teton) — schematic netlist excerpt (pin names and nets, part order shuffled) for the footprints in the layout excerpt that follows; sources: Cadence DE-HDL packaged netlist, KiCad conversion of 03242023_DA0F0TMBIJ0_F0T_Motherboard_J_brd_V01_OCP.brd

U324  MOSFET_NCH_GDS_ESD_PROTECTED  2N7002K IC  pkg SOT23_GDSXC  page 260
  D  = VR_P5V_EN_D
  G  = VR_P5V_EN_N
  S  = GND

C399  Q_CAP  22UF 4V 20% X6S  pkg C0402  page 74 : A = PVCCD_HV_CPU0 ; B = GND

(kicad_pcb
	(version 20260206)
	(generator "pcbnew")
	(generator_version "10.0")
	(general
		(thickness 1.6)
		(legacy_teardrops no)
	)
	(paper "A4")
	(title_block
		(title "03242023_DA0F0TMBIJ0_F0T_Motherboard_J_brd_V01_OCP.brd")
		(comment 1 "Grand Teton / footprints 1332-1333 of 6105")
	)
	(layers
		(0 "F.Cu" signal "TOP")
		(4 "In1.Cu" signal "GND")
		(6 "In2.Cu" signal "IN1")
		(8 "In3.Cu" signal "GND1")
		(10 "In4.Cu" signal "IN2")
		(12 "In5.Cu" signal "GND2")
		(14 "In6.Cu" signal "IN3")
		(16 "In7.Cu" signal "GND3")
		(18 "In8.Cu" signal "VCC")
		(20 "In9.Cu" signal "VCC1")
		(22 "In10.Cu" signal "GND4")
		(24 "In11.Cu" signal "IN4")
		(26 "In12.Cu" signal "GND5")
		(28 "In13.Cu" signal "IN5")
		(30 "In14.Cu" signal "GND6")
		(32 "In15.Cu" signal "IN6")
		(34 "In16.Cu" signal "GND7")
		(2 "B.Cu" signal "BOTTOM")
		(9 "F.Adhes" user "F.Adhesive")
		(11 "B.Adhes" user "B.Adhesive")
		(13 "F.Paste" user "Package Geometry/Pastemask Top")
		(15 "B.Paste" user "Package Geometry/Pastemask Bottom")
		(5 "F.SilkS" user "Ref Des/Silkscreen Top")
		(7 "B.SilkS" user "Ref Des/Silkscreen Bottom")
		(1 "F.Mask" user "Board Geometry/Soldermask Top")
		(3 "B.Mask" user "Board Geometry/Soldermask Bottom")
		(17 "Dwgs.User" user "User.Drawings")
		(19 "Cmts.User" user "User.Comments")
		(21 "Eco1.User" user "User.Eco1")
		(23 "Eco2.User" user "User.Eco2")
		(25 "Edge.Cuts" user "Board Geometry/Outline")
		(27 "Margin" user)
		(31 "F.CrtYd" user "Package Geometry/Place Bound Top")
		(29 "B.CrtYd" user "Package Geometry/Place Bound Bottom")
		(35 "F.Fab" user "Ref Des/Assembly Top")
		(33 "B.Fab" user "Ref Des/Assembly Bottom")
	)
	(footprint ""
		(layer "F.Cu")
		(at 164.211 -125.73 180)
		(property "Reference" "U324"
			(at -3.07721 -2.33426 90)
			(unlocked yes)
			(layer "F.SilkS")
			(effects
				(font
					(size 0.7874 0.5842)
					(thickness 0.1524)
				)
				(justify left)
			)
		)
		(property "Value" ""
			(at 0 0 180)
			(layer "F.Fab")
			(effects
				(font
					(size 1.27 1.27)
				)
			)
		)
		(duplicate_pad_numbers_are_jumpers no)
		(fp_line
			(start 1.603248 1.500124)
			(end -1.603248 1.500124)
			(stroke
				(width 0.1524)
				(type default)
			)
			(layer "F.SilkS")
		)
		(fp_line
			(start 1.603248 -1.500124)
			(end 1.603248 1.500124)
			(stroke
				(width 0.1524)
				(type default)
			)
			(layer "F.SilkS")
		)
		(fp_line
			(start -1.603248 1.500124)
			(end -1.603248 -1.500124)
			(stroke
				(width 0.1524)
				(type default)
			)
			(layer "F.SilkS")
		)
		(fp_line
			(start -1.603248 -1.500124)
			(end 1.603248 -1.500124)
			(stroke
				(width 0.1524)
				(type default)
			)
			(layer "F.SilkS")
		)
		(fp_line
			(start 1.249934 0.219964)
			(end 1.249934 -0.219964)
			(stroke
				(width 0.1)
				(type default)
			)
			(layer "F.Fab")
		)
		(fp_line
			(start 1.249934 -0.219964)
			(end 0.700024 -0.219964)
			(stroke
				(width 0.1)
				(type default)
			)
			(layer "F.Fab")
		)
		(fp_line
			(start 0.700024 1.500124)
			(end 0.700024 0.219964)
			(stroke
				(width 0.1)
				(type default)
			)
			(layer "F.Fab")
		)
		(fp_line
			(start 0.700024 0.219964)
			(end 1.249934 0.219964)
			(stroke
				(width 0.1)
				(type default)
			)
			(layer "F.Fab")
		)
		(fp_line
			(start 0.700024 -0.219964)
			(end 0.700024 -1.500124)
			(stroke
				(width 0.1)
				(type default)
			)
			(layer "F.Fab")
		)
		(fp_line
			(start 0.700024 -1.500124)
			(end -0.700024 -1.500124)
			(stroke
				(width 0.1)
				(type default)
			)
			(layer "F.Fab")
		)
		(fp_line
			(start -0.6985 0.729996)
			(end -1.249934 0.729996)
			(stroke
				(width 0.1)
				(type default)
			)
			(layer "F.Fab")
		)
		(fp_line
			(start -0.6985 -0.729996)
			(end -0.6985 0.729996)
			(stroke
				(width 0.1)
				(type default)
			)
			(layer "F.Fab")
		)
		(fp_line
			(start -0.700024 1.500124)
			(end 0.700024 1.500124)
			(stroke
				(width 0.1)
				(type default)
			)
			(layer "F.Fab")
		)
		(fp_line
			(start -0.700024 1.169924)
			(end -0.700024 1.500124)
			(stroke
				(width 0.1)
				(type default)
			)
			(layer "F.Fab")
		)
		(fp_line
			(start -0.700024 -1.169924)
			(end -1.249934 -1.169924)
			(stroke
				(width 0.1)
				(type default)
			)
			(layer "F.Fab")
		)
		(fp_line
			(start -0.700024 -1.500124)
			(end -0.700024 -1.169924)
			(stroke
				(width 0.1)
				(type default)
			)
			(layer "F.Fab")
		)
		(fp_line
			(start -1.249934 1.169924)
			(end -0.700024 1.169924)
			(stroke
				(width 0.1)
				(type default)
			)
			(layer "F.Fab")
		)
		(fp_line
			(start -1.249934 0.729996)
			(end -1.249934 1.169924)
			(stroke
				(width 0.1)
				(type default)
			)
			(layer "F.Fab")
		)
		(fp_line
			(start -1.249934 -0.729996)
			(end -0.6985 -0.729996)
			(stroke
				(width 0.1)
				(type default)
			)
			(layer "F.Fab")
		)
		(fp_line
			(start -1.249934 -1.169924)
			(end -1.249934 -0.729996)
			(stroke
				(width 0.1)
				(type default)
			)
			(layer "F.Fab")
		)
		(fp_rect
			(start -0.700024 1.500124)
			(end 0.700024 -1.500124)
			(stroke
				(width 0)
				(type default)
			)
			(fill no)
			(layer "F.Fab")
		)
		(pad "D" smd rect
			(at 0.999998 0 90)
			(size 0.8128 0.9144)
			(layers "F.Cu" "F.Mask" "F.Paste")
			(net "VR_P5V_EN_D")
		)
		(pad "G" smd rect
			(at -0.999998 -0.94996 90)
			(size 0.8128 0.9144)
			(layers "F.Cu" "F.Mask" "F.Paste")
			(net "VR_P5V_EN_N")
		)
		(pad "S" smd rect
			(at -0.999998 0.94996 90)
			(size 0.8128 0.9144)
			(layers "F.Cu" "F.Mask" "F.Paste")
			(net "GND")
		)
	)
	(footprint ""
		(layer "F.Cu")
		(at 367.44783 -247.715024 90)
		(property "Reference" "C399"
			(at 0 0 90)
			(layer "F.SilkS")
			(hide yes)
			(effects
				(font
					(size 1.27 1.27)
				)
			)
		)
		(property "Value" ""
			(at 0 0 90)
			(layer "F.Fab")
			(effects
				(font
					(size 1.27 1.27)
				)
			)
		)
		(duplicate_pad_numbers_are_jumpers no)
		(fp_line
			(start 0.7874 -0.4064)
			(end 0.7874 0.4064)
			(stroke
				(width 0.1524)
				(type default)
			)
			(layer "F.SilkS")
		)
		(fp_line
			(start -0.7874 -0.4064)
			(end 0.7874 -0.4064)
			(stroke
				(width 0.1524)
				(type default)
			)
			(layer "F.SilkS")
		)
		(fp_line
			(start 0.7874 0.4064)
			(end -0.7874 0.4064)
			(stroke
				(width 0.1524)
				(type default)
			)
			(layer "F.SilkS")
		)
		(fp_line
			(start -0.7874 0.4064)
			(end -0.7874 -0.4064)
			(stroke
				(width 0.1524)
				(type default)
			)
			(layer "F.SilkS")
		)
		(fp_line
			(start -0.12065 -0.305054)
			(end -0.12065 -0.2794)
			(stroke
				(width 0.1)
				(type default)
			)
			(layer "F.Fab")
		)
		(fp_line
			(start -0.67945 -0.305054)
			(end -0.12065 -0.305054)
			(stroke
				(width 0.1)
				(type default)
			)
			(layer "F.Fab")
		)
		(fp_line
			(start 0.67945 -0.3048)
			(end 0.67945 0.3048)
			(stroke
				(width 0.1)
				(type default)
			)
			(layer "F.Fab")
		)
		(fp_line
			(start 0.12065 -0.3048)
			(end 0.67945 -0.3048)
			(stroke
				(width 0.1)
				(type default)
			)
			(layer "F.Fab")
		)
		(fp_line
			(start 0.12065 -0.2794)
			(end 0.12065 -0.3048)
			(stroke
				(width 0.1)
				(type default)
			)
			(layer "F.Fab")
		)
		(fp_line
			(start -0.12065 -0.2794)
			(end 0.12065 -0.2794)
			(stroke
				(width 0.1)
				(type default)
			)
			(layer "F.Fab")
		)
		(fp_line
			(start 0.120396 0.2794)
			(end -0.12065 0.2794)
			(stroke
				(width 0.1)
				(type default)
			)
			(layer "F.Fab")
		)
		(fp_line
			(start -0.12065 0.2794)
			(end -0.12065 0.3048)
			(stroke
				(width 0.1)
				(type default)
			)
			(layer "F.Fab")
		)
		(fp_line
			(start 0.67945 0.3048)
			(end 0.120396 0.3048)
			(stroke
				(width 0.1)
				(type default)
			)
			(layer "F.Fab")
		)
		(fp_line
			(start 0.120396 0.3048)
			(end 0.120396 0.2794)
			(stroke
				(width 0.1)
				(type default)
			)
			(layer "F.Fab")
		)
		(fp_line
			(start -0.12065 0.3048)
			(end -0.67945 0.3048)
			(stroke
				(width 0.1)
				(type default)
			)
			(layer "F.Fab")
		)
		(fp_line
			(start -0.67945 0.3048)
			(end -0.67945 -0.305054)
			(stroke
				(width 0.1)
				(type default)
			)
			(layer "F.Fab")
		)
		(pad "1" smd circle
			(at -0.40005 0 90)
			(size 0 0)
			(layers "F.Cu" "F.Mask" "F.Paste")
			(net "PVCCD_HV_CPU0")
		)
		(pad "2" smd circle
			(at 0.40005 0 90)
			(size 0 0)
			(layers "F.Cu" "F.Mask" "F.Paste")
			(net "GND")
		)
	)
)
